# BASEBOARD_FAB2 (Tioga Pass) — schematic netlist excerpt (pin names and nets, part order shuffled) for the footprints in the layout excerpt that follows; sources: Cadence DE-HDL packaged netlist, KiCad conversion of Wiwynn_Tioga_Pass_MB.brd

J1A1  SCONN288_H44441004  SCONN  pkg PIP  page 87
  \12v\(1)  = P12V_NVDIMM_KLM
  VSS(93)  = GND
  DQ(4)  = M_M_DQ<5>
  VSS(92)  = GND
  DQ(0)  = M_M_DQ<1>
  VSS(91)  = GND
  DQS9P  = M_M_DQS_DP<9>
  DQS9N  = M_M_DQS_DN<9>
  VSS(90)  = GND
  DQ(6)  = M_M_DQ<7>
  VSS(89)  = GND
  DQ(2)  = M_M_DQ<3>
  VSS(88)  = GND
  DQ(12)  = M_M_DQ<13>
  VSS(87)  = GND
  DQ(8)  = M_M_DQ<9>
  VSS(86)  = GND
  DQS10P  = M_M_DQS_DP<10>
  DQS10N  = M_M_DQS_DN<10>
  VSS(85)  = GND
  DQ(14)  = M_M_DQ<15>
  VSS(84)  = GND
  DQ(10)  = M_M_DQ<11>
  VSS(83)  = GND
  DQ(20)  = M_M_DQ<21>
  VSS(82)  = GND
  DQ(16)  = M_M_DQ<17>
  VSS(81)  = GND
  DQS11P  = M_M_DQS_DP<11>
  DQS11N  = M_M_DQS_DN<11>
  VSS(80)  = GND
  DQ(22)  = M_M_DQ<23>
  VSS(79)  = GND
  DQ(18)  = M_M_DQ<19>
  VSS(78)  = GND
  DQ(28)  = M_M_DQ<29>
  VSS(77)  = GND
  DQ(24)  = M_M_DQ<25>
  VSS(76)  = GND
  DQS12P  = M_M_DQS_DP<12>
  DQS12N  = M_M_DQS_DN<12>
  VSS(75)  = GND
  DQ(30)  = M_M_DQ<31>
  VSS(74)  = GND
  DQ(26)  = M_M_DQ<27>
  VSS(73)  = GND
  CB(4)  = M_M_ECC<5>
  VSS(72)  = GND
  CB(0)  = M_M_ECC<1>
  VSS(71)  = GND
  DQS17P  = M_M_DQS_DP<17>
  DQS17N  = M_M_DQS_DN<17>
  VSS(70)  = GND
  CB(6)  = M_M_ECC<7>
  VSS(69)  = GND
  CB(2)  = M_M_ECC<3>
  VSS(68)  = GND
  RESET_N  = M_KLM_RST_N
  VDD(25)  = PVDDQ_KLM
  CKE(0)  = M_M_CKE<0>
  VDD(24)  = PVDDQ_KLM
  ACT_N  = M_M_ACT_N
  BG(0)  = M_M_BG<0>
  VDD(23)  = PVDDQ_KLM
  A12  = M_M_MA<12>
  A9  = M_M_MA<9>
  VDD(22)  = PVDDQ_KLM
  A8  = M_M_MA<8>
  A6  = M_M_MA<6>
  VDD(21)  = PVDDQ_KLM
  A3  = M_M_MA<3>
  A1  = M_M_MA<1>
  VDD(20)  = PVDDQ_KLM
  CK0P  = M_M_CLK_DP<0>
  CK0N  = M_M_CLK_DN<0>
  VDD(19)  = PVDDQ_KLM
  VTT(1)  = PVTT_KLM
  EVENT_N  = FM_DIMM_EVENT_COD_N
  A0  = M_M_MA<0>
  VDD(18)  = PVDDQ_KLM
  BA(0)  = M_M_BA<0>
  A16_RAS_N  = M_M_MA<16>
  VDD(17)  = PVDDQ_KLM
  S0_N  = M_M_CS_N<0>
  VDD(16)  = PVDDQ_KLM
  A15_CAS_N  = M_M_MA<15>
  ODT(0)  = M_M_ODT<0>
  VDD(15)  = PVDDQ_KLM
  S1_N  = M_M_CS_N<1>
  VDD(14)  = PVDDQ_KLM
  ODT(1)  = M_M_ODT<1>
  VDD(13)  = PVDDQ_KLM
  S2_N_C(0)  = M_M_CS_N<2>
  VSS(67)  = GND
  DQ(36)  = M_M_DQ<37>
  VSS(66)  = GND
  DQ(32)  = M_M_DQ<33>
  VSS(65)  = GND
  DQS13P  = M_M_DQS_DP<13>
  DQS13N  = M_M_DQS_DN<13>
  VSS(64)  = GND
  DQ(38)  = M_M_DQ<39>
  VSS(63)  = GND
  DQ(34)  = M_M_DQ<35>
  VSS(62)  = GND
  DQ(44)  = M_M_DQ<45>
  VSS(61)  = GND
  DQ(40)  = M_M_DQ<41>
  VSS(60)  = GND
  DQS14P  = M_M_DQS_DP<14>
  DQS14N  = M_M_DQS_DN<14>
  VSS(59)  = GND
  DQ(46)  = M_M_DQ<47>
  VSS(58)  = GND
  DQ(42)  = M_M_DQ<43>
  VSS(57)  = GND
  DQ(52)  = M_M_DQ<53>
  VSS(56)  = GND
  DQ(48)  = M_M_DQ<49>
  VSS(55)  = GND
  DQS15P  = M_M_DQS_DP<15>
  DQS15N  = M_M_DQS_DN<15>
  VSS(54)  = GND
  DQ(54)  = M_M_DQ<55>
  VSS(53)  = GND
  DQ(50)  = M_M_DQ<51>
  VSS(52)  = GND
  DQ(60)  = M_M_DQ<61>
  VSS(51)  = GND
  DQ(56)  = M_M_DQ<57>
  VSS(50)  = GND
  DQS16P  = M_M_DQS_DP<16>
  DQS16N  = M_M_DQS_DN<16>
  VSS(49)  = GND
  DQ(62)  = M_M_DQ<63>
  VSS(48)  = GND
  DQ(58)  = M_M_DQ<59>
  VSS(47)  = GND
  SA(0)  = GND
  SA(1)  = GND
  SCL  = SMB_DDR_KLM_VPP_SCL
  VPP(4)  = PVPP_KLM
  VPP(3)  = PVPP_KLM
  RFU(2)  = TP_CH_M_DIMM_M0_RFU_2
  \12v\(0)  = P12V_NVDIMM_KLM
  VREFCA  = M_M_VREF
  VSS(46)  = GND
  DQ(5)  = M_M_DQ<4>
  VSS(45)  = GND
  DQ(1)  = M_M_DQ<0>
  VSS(44)  = GND
  DQS0N  = M_M_DQS_DN<0>
  DQS0P  = M_M_DQS_DP<0>
  VSS(43)  = GND
  DQ(7)  = M_M_DQ<6>
  VSS(42)  = GND
  DQ(3)  = M_M_DQ<2>
  VSS(41)  = GND
  DQ(13)  = M_M_DQ<12>
  VSS(40)  = GND
  DQ(9)  = M_M_DQ<8>
  VSS(39)  = GND
  DQS1N  = M_M_DQS_DN<1>
  DQS1P  = M_M_DQS_DP<1>
  VSS(38)  = GND
  DQ(15)  = M_M_DQ<14>
  VSS(37)  = GND
  DQ(11)  = M_M_DQ<10>
  VSS(36)  = GND
  DQ(21)  = M_M_DQ<20>
  VSS(35)  = GND
  DQ(17)  = M_M_DQ<16>
  VSS(34)  = GND
  DQS2N  = M_M_DQS_DN<2>
  DQS2P  = M_M_DQS_DP<2>
  VSS(33)  = GND
  DQ(23)  = M_M_DQ<22>
  VSS(32)  = GND
  DQ(19)  = M_M_DQ<18>
  VSS(31)  = GND
  DQ(29)  = M_M_DQ<28>
  VSS(30)  = GND
  DQ(25)  = M_M_DQ<24>
  VSS(29)  = GND
  DQS3N  = M_M_DQS_DN<3>
  DQS3P  = M_M_DQS_DP<3>
  VSS(28)  = GND
  DQ(31)  = M_M_DQ<30>
  VSS(27)  = GND
  DQ(27)  = M_M_DQ<26>
  VSS(26)  = GND
  CB(5)  = M_M_ECC<4>
  VSS(25)  = GND
  CB(1)  = M_M_ECC<0>
  VSS(24)  = GND
  DQS8N  = M_M_DQS_DN<8>
  DQS8P  = M_M_DQS_DP<8>
  VSS(23)  = GND
  CB(7)  = M_M_ECC<6>
  VSS(22)  = GND
  CB(3)  = M_M_ECC<2>
  VSS(21)  = GND
  CKE(1)  = M_M_CKE<1>
  VDD(12)  = PVDDQ_KLM
  RFU(0)  = TP_CH_M_DIMM_M0_RFU_0
  VDD(11)  = PVDDQ_KLM
  BG(1)  = M_M_BG<1>
  ALERT_N  = M_M_ALERT_N
  VDD(10)  = PVDDQ_KLM
  A11  = M_M_MA<11>
  A7  = M_M_MA<7>
  VDD(9)  = PVDDQ_KLM
  A5  = M_M_MA<5>
  A4  = M_M_MA<4>
  VDD(8)  = PVDDQ_KLM
  A2  = M_M_MA<2>
  VDD(7)  = PVDDQ_KLM
  CK1P  = M_M_CLK_DP<1>
  CK1N  = M_M_CLK_DN<1>
  VDD(6)  = PVDDQ_KLM
  VTT(0)  = PVTT_KLM
  PAR  = M_M_PAR
  VDD(5)  = PVDDQ_KLM
  BA(1)  = M_M_BA<1>
  A10  = M_M_MA<10>
  VDD(4)  = PVDDQ_KLM
  RFU(1)  = TP_CH_M_DIMM_M0_RFU_1
  A14_WE_N  = M_M_MA<14>
  VDD(3)  = PVDDQ_KLM
  SAVE_N_NC  = FM_ADR_COMPLETE_KLM_N
  VDD(2)  = PVDDQ_KLM
  A13  = M_M_MA<13>
  VDD(1)  = PVDDQ_KLM
  A17  = M_M_MA<17>
  C(2)  = M_M_C<2>
  VDD(0)  = PVDDQ_KLM
  S3_N_C(1)  = M_M_CS_N<3>
  SA(2)  = PVPP_KLM
  VSS(20)  = GND
  DQ(37)  = M_M_DQ<36>
  VSS(19)  = GND
  DQ(33)  = M_M_DQ<32>
  VSS(18)  = GND
  DQS4N  = M_M_DQS_DN<4>
  DQS4P  = M_M_DQS_DP<4>
  VSS(17)  = GND
  DQ(39)  = M_M_DQ<38>
  VSS(16)  = GND
  DQ(35)  = M_M_DQ<34>
  VSS(15)  = GND
  DQ(45)  = M_M_DQ<44>
  VSS(14)  = GND
  DQ(41)  = M_M_DQ<40>
  VSS(13)  = GND
  DQS5N  = M_M_DQS_DN<5>
  DQS5P  = M_M_DQS_DP<5>
  VSS(12)  = GND
  DQ(47)  = M_M_DQ<46>
  VSS(11)  = GND
  DQ(43)  = M_M_DQ<42>
  VSS(10)  = GND
  DQ(53)  = M_M_DQ<52>
  VSS(9)  = GND
  DQ(49)  = M_M_DQ<48>
  VSS(8)  = GND
  DQS6N  = M_M_DQS_DN<6>
  DQS6P  = M_M_DQS_DP<6>
  VSS(7)  = GND
  DQ(55)  = M_M_DQ<54>
  VSS(6)  = GND
  DQ(51)  = M_M_DQ<50>
  VSS(5)  = GND
  DQ(61)  = M_M_DQ<60>
  VSS(4)  = GND
  DQ(57)  = M_M_DQ<56>
  VSS(3)  = GND
  DQS7N  = M_M_DQS_DN<7>
  DQS7P  = M_M_DQS_DP<7>
  VSS(2)  = GND
  DQ(63)  = M_M_DQ<62>
  VSS(1)  = GND
  DQ(59)  = M_M_DQ<58>
  VSS(0)  = GND
  VDDSPD  = PVPP_KLM
  SDA  = SMB_DDR_KLM_VPP_SDA
  VPP(1)  = PVPP_KLM
  VPP(0)  = PVPP_KLM
  VPP(2)  = PVPP_KLM

(kicad_pcb
	(version 20260206)
	(generator "pcbnew")
	(generator_version "10.0")
	(general
		(thickness 1.6)
		(legacy_teardrops no)
	)
	(paper "A4")
	(title_block
		(title "Wiwynn_Tioga_Pass_MB.brd")
		(comment 1 "Tioga Pass / footprint 830 of 4770 (J1A1), pads 252-291 of 291")
	)
	(layers
		(0 "F.Cu" signal "TOP")
		(4 "In1.Cu" signal "L2GND")
		(6 "In2.Cu" signal "L3")
		(8 "In3.Cu" signal "L4GND")
		(10 "In4.Cu" signal "L5")
		(12 "In5.Cu" signal "L6GND")
		(14 "In6.Cu" signal "L7VCC")
		(16 "In7.Cu" signal "L8VCC")
		(18 "In8.Cu" signal "L9GND")
		(20 "In9.Cu" signal "L10")
		(22 "In10.Cu" signal "L11GND")
		(24 "In11.Cu" signal "L12")
		(26 "In12.Cu" signal "L13GND")
		(2 "B.Cu" signal "BOTTOM")
		(9 "F.Adhes" user "F.Adhesive")
		(11 "B.Adhes" user "B.Adhesive")
		(13 "F.Paste" user "Package Geometry/Pastemask Top")
		(15 "B.Paste" user "Package Geometry/Pastemask Bottom")
		(5 "F.SilkS" user "Ref Des/Silkscreen Top")
		(7 "B.SilkS" user "Ref Des/Silkscreen Bottom")
		(1 "F.Mask" user "Board Geometry/Soldermask Top")
		(3 "B.Mask" user "Board Geometry/Soldermask Bottom")
		(17 "Dwgs.User" user "User.Drawings")
		(19 "Cmts.User" user "User.Comments")
		(21 "Eco1.User" user "User.Eco1")
		(23 "Eco2.User" user "User.Eco2")
		(25 "Edge.Cuts" user "Board Geometry/Outline")
		(27 "Margin" user)
		(31 "F.CrtYd" user "Package Geometry/Place Bound Top")
		(29 "B.CrtYd" user "Package Geometry/Place Bound Bottom")
		(35 "F.Fab" user "Ref Des/Assembly Top")
		(33 "B.Fab" user "Ref Des/Assembly Bottom")
	)
	(footprint ""
		(layer "F.Cu")
		(at 29.699458 -152.273 90)
		(property "Reference" "J1A1"
			(at -2.572512 42.563542 0)
			(unlocked yes)
			(layer "F.SilkS")
			(effects
				(font
					(size 0.7874 0.5842)
					(thickness 0.1524)
				)
				(justify left)
			)
		)
		(property "Value" ""
			(at 0 0 90)
			(layer "F.Fab")
			(effects
				(font
					(size 1.27 1.27)
				)
			)
		)
		(duplicate_pad_numbers_are_jumpers no)
		(pad "249" smd rect
			(at 4.59994 93.49994 90)
			(size 1.8034 0.508)
			(layers "F.Cu" "F.Mask" "F.Paste")
			(net "M_M_DQ<34>")
		)
		(pad "250" smd rect
			(at 4.59994 94.350078 90)
			(size 1.8034 0.508)
			(layers "F.Cu" "F.Mask" "F.Paste")
			(net "GND")
		)
		(pad "251" smd rect
			(at 4.59994 95.199962 90)
			(size 1.8034 0.508)
			(layers "F.Cu" "F.Mask" "F.Paste")
			(net "M_M_DQ<44>")
		)
		(pad "252" smd rect
			(at 4.59994 96.0501 90)
			(size 1.8034 0.508)
			(layers "F.Cu" "F.Mask" "F.Paste")
			(net "GND")
		)
		(pad "253" smd rect
			(at 4.59994 96.899984 90)
			(size 1.8034 0.508)
			(layers "F.Cu" "F.Mask" "F.Paste")
			(net "M_M_DQ<40>")
		)
		(pad "254" smd rect
			(at 4.59994 97.750122 90)
			(size 1.8034 0.508)
			(layers "F.Cu" "F.Mask" "F.Paste")
			(net "GND")
		)
		(pad "255" smd rect
			(at 4.59994 98.600006 90)
			(size 1.8034 0.508)
			(layers "F.Cu" "F.Mask" "F.Paste")
			(net "M_M_DQS_DN<5>")
		)
		(pad "256" smd rect
			(at 4.59994 99.44989 90)
			(size 1.8034 0.508)
			(layers "F.Cu" "F.Mask" "F.Paste")
			(net "M_M_DQS_DP<5>")
		)
		(pad "257" smd rect
			(at 4.59994 100.300028 90)
			(size 1.8034 0.508)
			(layers "F.Cu" "F.Mask" "F.Paste")
			(net "GND")
		)
		(pad "258" smd rect
			(at 4.59994 101.149912 90)
			(size 1.8034 0.508)
			(layers "F.Cu" "F.Mask" "F.Paste")
			(net "M_M_DQ<46>")
		)
		(pad "259" smd rect
			(at 4.59994 102.00005 90)
			(size 1.8034 0.508)
			(layers "F.Cu" "F.Mask" "F.Paste")
			(net "GND")
		)
		(pad "260" smd rect
			(at 4.59994 102.849934 90)
			(size 1.8034 0.508)
			(layers "F.Cu" "F.Mask" "F.Paste")
			(net "M_M_DQ<42>")
		)
		(pad "261" smd rect
			(at 4.59994 103.700072 90)
			(size 1.8034 0.508)
			(layers "F.Cu" "F.Mask" "F.Paste")
			(net "GND")
		)
		(pad "262" smd rect
			(at 4.59994 104.549956 90)
			(size 1.8034 0.508)
			(layers "F.Cu" "F.Mask" "F.Paste")
			(net "M_M_DQ<52>")
		)
		(pad "263" smd rect
			(at 4.59994 105.400094 90)
			(size 1.8034 0.508)
			(layers "F.Cu" "F.Mask" "F.Paste")
			(net "GND")
		)
		(pad "264" smd rect
			(at 4.59994 106.249978 90)
			(size 1.8034 0.508)
			(layers "F.Cu" "F.Mask" "F.Paste")
			(net "M_M_DQ<48>")
		)
		(pad "265" smd rect
			(at 4.59994 107.100116 90)
			(size 1.8034 0.508)
			(layers "F.Cu" "F.Mask" "F.Paste")
			(net "GND")
		)
		(pad "266" smd rect
			(at 4.59994 107.95 90)
			(size 1.8034 0.508)
			(layers "F.Cu" "F.Mask" "F.Paste")
			(net "M_M_DQS_DN<6>")
		)
		(pad "267" smd rect
			(at 4.59994 108.799884 90)
			(size 1.8034 0.508)
			(layers "F.Cu" "F.Mask" "F.Paste")
			(net "M_M_DQS_DP<6>")
		)
		(pad "268" smd rect
			(at 4.59994 109.650022 90)
			(size 1.8034 0.508)
			(layers "F.Cu" "F.Mask" "F.Paste")
			(net "GND")
		)
		(pad "269" smd rect
			(at 4.59994 110.499906 90)
			(size 1.8034 0.508)
			(layers "F.Cu" "F.Mask" "F.Paste")
			(net "M_M_DQ<54>")
		)
		(pad "270" smd rect
			(at 4.59994 111.350044 90)
			(size 1.8034 0.508)
			(layers "F.Cu" "F.Mask" "F.Paste")
			(net "GND")
		)
		(pad "271" smd rect
			(at 4.59994 112.199928 90)
			(size 1.8034 0.508)
			(layers "F.Cu" "F.Mask" "F.Paste")
			(net "M_M_DQ<50>")
		)
		(pad "272" smd rect
			(at 4.59994 113.050066 90)
			(size 1.8034 0.508)
			(layers "F.Cu" "F.Mask" "F.Paste")
			(net "GND")
		)
		(pad "273" smd rect
			(at 4.59994 113.89995 90)
			(size 1.8034 0.508)
			(layers "F.Cu" "F.Mask" "F.Paste")
			(net "M_M_DQ<60>")
		)
		(pad "274" smd rect
			(at 4.59994 114.750088 90)
			(size 1.8034 0.508)
			(layers "F.Cu" "F.Mask" "F.Paste")
			(net "GND")
		)
		(pad "275" smd rect
			(at 4.59994 115.599972 90)
			(size 1.8034 0.508)
			(layers "F.Cu" "F.Mask" "F.Paste")
			(net "M_M_DQ<56>")
		)
		(pad "276" smd rect
			(at 4.59994 116.45011 90)
			(size 1.8034 0.508)
			(layers "F.Cu" "F.Mask" "F.Paste")
			(net "GND")
		)
		(pad "277" smd rect
			(at 4.59994 117.299994 90)
			(size 1.8034 0.508)
			(layers "F.Cu" "F.Mask" "F.Paste")
			(net "M_M_DQS_DN<7>")
		)
		(pad "278" smd rect
			(at 4.59994 118.149878 90)
			(size 1.8034 0.508)
			(layers "F.Cu" "F.Mask" "F.Paste")
			(net "M_M_DQS_DP<7>")
		)
		(pad "279" smd rect
			(at 4.59994 119.000016 90)
			(size 1.8034 0.508)
			(layers "F.Cu" "F.Mask" "F.Paste")
			(net "GND")
		)
		(pad "280" smd rect
			(at 4.59994 119.8499 90)
			(size 1.8034 0.508)
			(layers "F.Cu" "F.Mask" "F.Paste")
			(net "M_M_DQ<62>")
		)
		(pad "281" smd rect
			(at 4.59994 120.700038 90)
			(size 1.8034 0.508)
			(layers "F.Cu" "F.Mask" "F.Paste")
			(net "GND")
		)
		(pad "282" smd rect
			(at 4.59994 121.549922 90)
			(size 1.8034 0.508)
			(layers "F.Cu" "F.Mask" "F.Paste")
			(net "M_M_DQ<58>")
		)
		(pad "283" smd rect
			(at 4.59994 122.40006 90)
			(size 1.8034 0.508)
			(layers "F.Cu" "F.Mask" "F.Paste")
			(net "GND")
		)
		(pad "284" smd rect
			(at 4.59994 123.249944 90)
			(size 1.8034 0.508)
			(layers "F.Cu" "F.Mask" "F.Paste")
			(net "PVPP_KLM")
		)
		(pad "285" smd rect
			(at 4.59994 124.100082 90)
			(size 1.8034 0.508)
			(layers "F.Cu" "F.Mask" "F.Paste")
			(net "SMB_DDR_KLM_VPP_SDA")
		)
		(pad "286" smd rect
			(at 4.59994 124.949966 90)
			(size 1.8034 0.508)
			(layers "F.Cu" "F.Mask" "F.Paste")
			(net "PVPP_KLM")
		)
		(pad "287" smd rect
			(at 4.59994 125.800104 90)
			(size 1.8034 0.508)
			(layers "F.Cu" "F.Mask" "F.Paste")
			(net "PVPP_KLM")
		)
		(pad "288" smd rect
			(at 4.59994 126.649988 90)
			(size 1.8034 0.508)
			(layers "F.Cu" "F.Mask" "F.Paste")
			(net "PVPP_KLM")
		)
	)
)
